(kicad_pcb
	(version 20260206)
	(generator "pcbnew")
	(generator_version "10.0")
	(general
		(thickness 1.6)
		(legacy_teardrops no)
	)
	(paper "A4")
	(title_block
		(title "01162023_DA0F0TEBIF0_F0T_Expander_BD_F_brd_V02_OCP.brd")
		(comment 1 "Grand Teton / footprints 3938-3944 of 9728")
	)
	(layers
		(0 "F.Cu" signal "TOP")
		(4 "In1.Cu" signal "GND")
		(6 "In2.Cu" signal "VCC")
		(8 "In3.Cu" signal "VCC1")
		(10 "In4.Cu" signal "GND1")
		(12 "In5.Cu" signal "IN1")
		(14 "In6.Cu" signal "GND2")
		(16 "In7.Cu" signal "IN2")
		(18 "In8.Cu" signal "GND3")
		(20 "In9.Cu" signal "IN3")
		(22 "In10.Cu" signal "GND4")
		(24 "In11.Cu" signal "IN4")
		(26 "In12.Cu" signal "GND5")
		(28 "In13.Cu" signal "IN5")
		(30 "In14.Cu" signal "GND6")
		(32 "In15.Cu" signal "IN6")
		(34 "In16.Cu" signal "GND7")
		(2 "B.Cu" signal "BOTTOM")
		(9 "F.Adhes" user "F.Adhesive")
		(11 "B.Adhes" user "B.Adhesive")
		(13 "F.Paste" user "Package Geometry/Pastemask Top")
		(15 "B.Paste" user "Package Geometry/Pastemask Bottom")
		(5 "F.SilkS" user "Ref Des/Silkscreen Top")
		(7 "B.SilkS" user "Ref Des/Silkscreen Bottom")
		(1 "F.Mask" user "Board Geometry/Soldermask Top")
		(3 "B.Mask" user "Board Geometry/Soldermask Bottom")
		(17 "Dwgs.User" user "User.Drawings")
		(19 "Cmts.User" user "User.Comments")
		(21 "Eco1.User" user "User.Eco1")
		(23 "Eco2.User" user "User.Eco2")
		(25 "Edge.Cuts" user "Board Geometry/Outline")
		(27 "Margin" user)
		(31 "F.CrtYd" user "Package Geometry/Place Bound Top")
		(29 "B.CrtYd" user "Package Geometry/Place Bound Bottom")
		(35 "F.Fab" user "Ref Des/Assembly Top")
		(33 "B.Fab" user "Ref Des/Assembly Bottom")
	)
	(footprint ""
		(layer "F.Cu")
		(at 323.917818 -223.389698 180)
		(property "Reference" "R2980"
			(at 0 0 180)
			(layer "F.SilkS")
			(hide yes)
			(effects
				(font
					(size 1.27 1.27)
				)
			)
		)
		(property "Value" ""
			(at 0 0 180)
			(layer "F.Fab")
			(effects
				(font
					(size 1.27 1.27)
				)
			)
		)
		(duplicate_pad_numbers_are_jumpers no)
		(fp_line
			(start 0.7874 0.4064)
			(end -0.7874 0.4064)
			(stroke
				(width 0.1524)
				(type default)
			)
			(layer "F.SilkS")
		)
		(fp_line
			(start 0.7874 -0.4064)
			(end 0.7874 0.4064)
			(stroke
				(width 0.1524)
				(type default)
			)
			(layer "F.SilkS")
		)
		(fp_line
			(start -0.7874 0.4064)
			(end -0.7874 -0.4064)
			(stroke
				(width 0.1524)
				(type default)
			)
			(layer "F.SilkS")
		)
		(fp_line
			(start -0.7874 -0.4064)
			(end 0.7874 -0.4064)
			(stroke
				(width 0.1524)
				(type default)
			)
			(layer "F.SilkS")
		)
		(fp_line
			(start 0.67945 0.3048)
			(end 0.120396 0.3048)
			(stroke
				(width 0.1)
				(type default)
			)
			(layer "F.Fab")
		)
		(fp_line
			(start 0.67945 -0.3048)
			(end 0.67945 0.3048)
			(stroke
				(width 0.1)
				(type default)
			)
			(layer "F.Fab")
		)
		(fp_line
			(start 0.12065 -0.2794)
			(end 0.12065 -0.3048)
			(stroke
				(width 0.1)
				(type default)
			)
			(layer "F.Fab")
		)
		(fp_line
			(start 0.12065 -0.3048)
			(end 0.67945 -0.3048)
			(stroke
				(width 0.1)
				(type default)
			)
			(layer "F.Fab")
		)
		(fp_line
			(start 0.120396 0.3048)
			(end 0.120396 0.2794)
			(stroke
				(width 0.1)
				(type default)
			)
			(layer "F.Fab")
		)
		(fp_line
			(start 0.120396 0.2794)
			(end -0.12065 0.2794)
			(stroke
				(width 0.1)
				(type default)
			)
			(layer "F.Fab")
		)
		(fp_line
			(start -0.12065 0.3048)
			(end -0.67945 0.3048)
			(stroke
				(width 0.1)
				(type default)
			)
			(layer "F.Fab")
		)
		(fp_line
			(start -0.12065 0.2794)
			(end -0.12065 0.3048)
			(stroke
				(width 0.1)
				(type default)
			)
			(layer "F.Fab")
		)
		(fp_line
			(start -0.12065 -0.2794)
			(end 0.12065 -0.2794)
			(stroke
				(width 0.1)
				(type default)
			)
			(layer "F.Fab")
		)
		(fp_line
			(start -0.12065 -0.305054)
			(end -0.12065 -0.2794)
			(stroke
				(width 0.1)
				(type default)
			)
			(layer "F.Fab")
		)
		(fp_line
			(start -0.67945 0.3048)
			(end -0.67945 -0.305054)
			(stroke
				(width 0.1)
				(type default)
			)
			(layer "F.Fab")
		)
		(fp_line
			(start -0.67945 -0.305054)
			(end -0.12065 -0.305054)
			(stroke
				(width 0.1)
				(type default)
			)
			(layer "F.Fab")
		)
		(pad "1" smd circle
			(at -0.40005 0 180)
			(size 0 0)
			(layers "F.Cu" "F.Mask" "F.Paste")
			(net "LED_POSTCODE_2")
		)
		(pad "2" smd circle
			(at 0.40005 0 180)
			(size 0 0)
			(layers "F.Cu" "F.Mask" "F.Paste")
			(net "LED_POSTCODE_R_2")
		)
	)
	(footprint ""
		(layer "F.Cu")
		(at 340.614 -205.232 -90)
		(property "Reference" "R4133"
			(at 0 0 270)
			(layer "F.SilkS")
			(hide yes)
			(effects
				(font
					(size 1.27 1.27)
				)
			)
		)
		(property "Value" ""
			(at 0 0 270)
			(layer "F.Fab")
			(effects
				(font
					(size 1.27 1.27)
				)
			)
		)
		(duplicate_pad_numbers_are_jumpers no)
		(fp_line
			(start -0.7874 0.4064)
			(end -0.7874 -0.4064)
			(stroke
				(width 0.1524)
				(type default)
			)
			(layer "F.SilkS")
		)
		(fp_line
			(start 0.7874 0.4064)
			(end -0.7874 0.4064)
			(stroke
				(width 0.1524)
				(type default)
			)
			(layer "F.SilkS")
		)
		(fp_line
			(start -0.7874 -0.4064)
			(end 0.7874 -0.4064)
			(stroke
				(width 0.1524)
				(type default)
			)
			(layer "F.SilkS")
		)
		(fp_line
			(start 0.7874 -0.4064)
			(end 0.7874 0.4064)
			(stroke
				(width 0.1524)
				(type default)
			)
			(layer "F.SilkS")
		)
		(fp_line
			(start -0.67945 0.3048)
			(end -0.67945 -0.305054)
			(stroke
				(width 0.1)
				(type default)
			)
			(layer "F.Fab")
		)
		(fp_line
			(start -0.12065 0.3048)
			(end -0.67945 0.3048)
			(stroke
				(width 0.1)
				(type default)
			)
			(layer "F.Fab")
		)
		(fp_line
			(start 0.120396 0.3048)
			(end 0.120396 0.2794)
			(stroke
				(width 0.1)
				(type default)
			)
			(layer "F.Fab")
		)
		(fp_line
			(start 0.67945 0.3048)
			(end 0.120396 0.3048)
			(stroke
				(width 0.1)
				(type default)
			)
			(layer "F.Fab")
		)
		(fp_line
			(start -0.12065 0.2794)
			(end -0.12065 0.3048)
			(stroke
				(width 0.1)
				(type default)
			)
			(layer "F.Fab")
		)
		(fp_line
			(start 0.120396 0.2794)
			(end -0.12065 0.2794)
			(stroke
				(width 0.1)
				(type default)
			)
			(layer "F.Fab")
		)
		(fp_line
			(start -0.12065 -0.2794)
			(end 0.12065 -0.2794)
			(stroke
				(width 0.1)
				(type default)
			)
			(layer "F.Fab")
		)
		(fp_line
			(start 0.12065 -0.2794)
			(end 0.12065 -0.3048)
			(stroke
				(width 0.1)
				(type default)
			)
			(layer "F.Fab")
		)
		(fp_line
			(start 0.12065 -0.3048)
			(end 0.67945 -0.3048)
			(stroke
				(width 0.1)
				(type default)
			)
			(layer "F.Fab")
		)
		(fp_line
			(start 0.67945 -0.3048)
			(end 0.67945 0.3048)
			(stroke
				(width 0.1)
				(type default)
			)
			(layer "F.Fab")
		)
		(fp_line
			(start -0.67945 -0.305054)
			(end -0.12065 -0.305054)
			(stroke
				(width 0.1)
				(type default)
			)
			(layer "F.Fab")
		)
		(fp_line
			(start -0.12065 -0.305054)
			(end -0.12065 -0.2794)
			(stroke
				(width 0.1)
				(type default)
			)
			(layer "F.Fab")
		)
		(pad "1" smd circle
			(at -0.40005 0 270)
			(size 0 0)
			(layers "F.Cu" "F.Mask" "F.Paste")
			(net "RST_SSD12_PERST_N")
		)
		(pad "2" smd circle
			(at 0.40005 0 270)
			(size 0 0)
			(layers "F.Cu" "F.Mask" "F.Paste")
			(net "RST_SSD12_PERST_R_N")
		)
	)
	(footprint ""
		(layer "F.Cu")
		(at 239.754918 -314.068714 180)
		(property "Reference" "PC249"
			(at 0 0 180)
			(layer "F.SilkS")
			(hide yes)
			(effects
				(font
					(size 1.27 1.27)
				)
			)
		)
		(property "Value" ""
			(at 0 0 180)
			(layer "F.Fab")
			(effects
				(font
					(size 1.27 1.27)
				)
			)
		)
		(duplicate_pad_numbers_are_jumpers no)
		(fp_line
			(start 1.524 0.762)
			(end -1.524 0.762)
			(stroke
				(width 0.1524)
				(type default)
			)
			(layer "F.SilkS")
		)
		(fp_line
			(start 1.524 -0.762)
			(end 1.524 0.762)
			(stroke
				(width 0.1524)
				(type default)
			)
			(layer "F.SilkS")
		)
		(fp_line
			(start -1.524 0.762)
			(end -1.524 -0.762)
			(stroke
				(width 0.1524)
				(type default)
			)
			(layer "F.SilkS")
		)
		(fp_line
			(start -1.524 -0.762)
			(end 1.524 -0.762)
			(stroke
				(width 0.1524)
				(type default)
			)
			(layer "F.SilkS")
		)
		(fp_line
			(start 1.1049 0.724916)
			(end 1.1049 -0.724916)
			(stroke
				(width 0.1)
				(type default)
			)
			(layer "F.Fab")
		)
		(fp_line
			(start 1.1049 -0.724916)
			(end -1.1049 -0.724916)
			(stroke
				(width 0.1)
				(type default)
			)
			(layer "F.Fab")
		)
		(fp_line
			(start -1.1049 0.724916)
			(end 1.1049 0.724916)
			(stroke
				(width 0.1)
				(type default)
			)
			(layer "F.Fab")
		)
		(fp_line
			(start -1.1049 -0.724916)
			(end -1.1049 0.724916)
			(stroke
				(width 0.1)
				(type default)
			)
			(layer "F.Fab")
		)
		(pad "1" smd rect
			(at -0.889 0)
			(size 1.016 1.27)
			(layers "F.Cu" "F.Mask" "F.Paste")
			(net "SW_P12V_P1V25_PEX2_FLT")
		)
		(pad "2" smd rect
			(at 0.889 0)
			(size 1.016 1.27)
			(layers "F.Cu" "F.Mask" "F.Paste")
			(net "GND")
		)
	)
	(footprint ""
		(layer "F.Cu")
		(at 396.209266 -89.500202 180)
		(property "Reference" "R1751"
			(at 0 0 180)
			(layer "F.SilkS")
			(hide yes)
			(effects
				(font
					(size 1.27 1.27)
				)
			)
		)
		(property "Value" ""
			(at 0 0 180)
			(layer "F.Fab")
			(effects
				(font
					(size 1.27 1.27)
				)
			)
		)
		(duplicate_pad_numbers_are_jumpers no)
		(fp_line
			(start 0.7874 0.4064)
			(end -0.7874 0.4064)
			(stroke
				(width 0.1524)
				(type default)
			)
			(layer "F.SilkS")
		)
		(fp_line
			(start 0.7874 -0.4064)
			(end 0.7874 0.4064)
			(stroke
				(width 0.1524)
				(type default)
			)
			(layer "F.SilkS")
		)
		(fp_line
			(start -0.7874 0.4064)
			(end -0.7874 -0.4064)
			(stroke
				(width 0.1524)
				(type default)
			)
			(layer "F.SilkS")
		)
		(fp_line
			(start -0.7874 -0.4064)
			(end 0.7874 -0.4064)
			(stroke
				(width 0.1524)
				(type default)
			)
			(layer "F.SilkS")
		)
		(fp_line
			(start 0.67945 0.3048)
			(end 0.120396 0.3048)
			(stroke
				(width 0.1)
				(type default)
			)
			(layer "F.Fab")
		)
		(fp_line
			(start 0.67945 -0.3048)
			(end 0.67945 0.3048)
			(stroke
				(width 0.1)
				(type default)
			)
			(layer "F.Fab")
		)
		(fp_line
			(start 0.12065 -0.2794)
			(end 0.12065 -0.3048)
			(stroke
				(width 0.1)
				(type default)
			)
			(layer "F.Fab")
		)
		(fp_line
			(start 0.12065 -0.3048)
			(end 0.67945 -0.3048)
			(stroke
				(width 0.1)
				(type default)
			)
			(layer "F.Fab")
		)
		(fp_line
			(start 0.120396 0.3048)
			(end 0.120396 0.2794)
			(stroke
				(width 0.1)
				(type default)
			)
			(layer "F.Fab")
		)
		(fp_line
			(start 0.120396 0.2794)
			(end -0.12065 0.2794)
			(stroke
				(width 0.1)
				(type default)
			)
			(layer "F.Fab")
		)
		(fp_line
			(start -0.12065 0.3048)
			(end -0.67945 0.3048)
			(stroke
				(width 0.1)
				(type default)
			)
			(layer "F.Fab")
		)
		(fp_line
			(start -0.12065 0.2794)
			(end -0.12065 0.3048)
			(stroke
				(width 0.1)
				(type default)
			)
			(layer "F.Fab")
		)
		(fp_line
			(start -0.12065 -0.2794)
			(end 0.12065 -0.2794)
			(stroke
				(width 0.1)
				(type default)
			)
			(layer "F.Fab")
		)
		(fp_line
			(start -0.12065 -0.305054)
			(end -0.12065 -0.2794)
			(stroke
				(width 0.1)
				(type default)
			)
			(layer "F.Fab")
		)
		(fp_line
			(start -0.67945 0.3048)
			(end -0.67945 -0.305054)
			(stroke
				(width 0.1)
				(type default)
			)
			(layer "F.Fab")
		)
		(fp_line
			(start -0.67945 -0.305054)
			(end -0.12065 -0.305054)
			(stroke
				(width 0.1)
				(type default)
			)
			(layer "F.Fab")
		)
		(pad "1" smd circle
			(at -0.40005 0 180)
			(size 0 0)
			(layers "F.Cu" "F.Mask" "F.Paste")
			(net "P3V3_AUX")
		)
		(pad "2" smd circle
			(at 0.40005 0 180)
			(size 0 0)
			(layers "F.Cu" "F.Mask" "F.Paste")
			(net "BIC_I2C6_MUX_A2")
		)
	)
	(footprint ""
		(layer "F.Cu")
		(at 79.462376 -22.937216 90)
		(property "Reference" "R1655"
			(at 0 0 90)
			(layer "F.SilkS")
			(hide yes)
			(effects
				(font
					(size 1.27 1.27)
				)
			)
		)
		(property "Value" ""
			(at 0 0 90)
			(layer "F.Fab")
			(effects
				(font
					(size 1.27 1.27)
				)
			)
		)
		(duplicate_pad_numbers_are_jumpers no)
		(fp_line
			(start 0.7874 -0.4064)
			(end 0.7874 0.4064)
			(stroke
				(width 0.1524)
				(type default)
			)
			(layer "F.SilkS")
		)
		(fp_line
			(start -0.7874 -0.4064)
			(end 0.7874 -0.4064)
			(stroke
				(width 0.1524)
				(type default)
			)
			(layer "F.SilkS")
		)
		(fp_line
			(start 0.7874 0.4064)
			(end -0.7874 0.4064)
			(stroke
				(width 0.1524)
				(type default)
			)
			(layer "F.SilkS")
		)
		(fp_line
			(start -0.7874 0.4064)
			(end -0.7874 -0.4064)
			(stroke
				(width 0.1524)
				(type default)
			)
			(layer "F.SilkS")
		)
		(fp_line
			(start -0.12065 -0.305054)
			(end -0.12065 -0.2794)
			(stroke
				(width 0.1)
				(type default)
			)
			(layer "F.Fab")
		)
		(fp_line
			(start -0.67945 -0.305054)
			(end -0.12065 -0.305054)
			(stroke
				(width 0.1)
				(type default)
			)
			(layer "F.Fab")
		)
		(fp_line
			(start 0.67945 -0.3048)
			(end 0.67945 0.3048)
			(stroke
				(width 0.1)
				(type default)
			)
			(layer "F.Fab")
		)
		(fp_line
			(start 0.12065 -0.3048)
			(end 0.67945 -0.3048)
			(stroke
				(width 0.1)
				(type default)
			)
			(layer "F.Fab")
		)
		(fp_line
			(start 0.12065 -0.2794)
			(end 0.12065 -0.3048)
			(stroke
				(width 0.1)
				(type default)
			)
			(layer "F.Fab")
		)
		(fp_line
			(start -0.12065 -0.2794)
			(end 0.12065 -0.2794)
			(stroke
				(width 0.1)
				(type default)
			)
			(layer "F.Fab")
		)
		(fp_line
			(start 0.120396 0.2794)
			(end -0.12065 0.2794)
			(stroke
				(width 0.1)
				(type default)
			)
			(layer "F.Fab")
		)
		(fp_line
			(start -0.12065 0.2794)
			(end -0.12065 0.3048)
			(stroke
				(width 0.1)
				(type default)
			)
			(layer "F.Fab")
		)
		(fp_line
			(start 0.67945 0.3048)
			(end 0.120396 0.3048)
			(stroke
				(width 0.1)
				(type default)
			)
			(layer "F.Fab")
		)
		(fp_line
			(start 0.120396 0.3048)
			(end 0.120396 0.2794)
			(stroke
				(width 0.1)
				(type default)
			)
			(layer "F.Fab")
		)
		(fp_line
			(start -0.12065 0.3048)
			(end -0.67945 0.3048)
			(stroke
				(width 0.1)
				(type default)
			)
			(layer "F.Fab")
		)
		(fp_line
			(start -0.67945 0.3048)
			(end -0.67945 -0.305054)
			(stroke
				(width 0.1)
				(type default)
			)
			(layer "F.Fab")
		)
		(pad "1" smd circle
			(at -0.40005 0 90)
			(size 0 0)
			(layers "F.Cu" "F.Mask" "F.Paste")
			(net "SMB_BIC_I2C9_MUX0_SSD2_R_SDA")
		)
		(pad "2" smd circle
			(at 0.40005 0 90)
			(size 0 0)
			(layers "F.Cu" "F.Mask" "F.Paste")
			(net "SMB_ISO_SSD2_SDA")
		)
	)
	(footprint ""
		(layer "F.Cu")
		(at 342.886792 -240.691162 90)
		(property "Reference" "R3584"
			(at 0 0 90)
			(layer "F.SilkS")
			(hide yes)
			(effects
				(font
					(size 1.27 1.27)
				)
			)
		)
		(property "Value" ""
			(at 0 0 90)
			(layer "F.Fab")
			(effects
				(font
					(size 1.27 1.27)
				)
			)
		)
		(duplicate_pad_numbers_are_jumpers no)
		(fp_line
			(start 0.7874 -0.4064)
			(end 0.7874 0.4064)
			(stroke
				(width 0.1524)
				(type default)
			)
			(layer "F.SilkS")
		)
		(fp_line
			(start -0.7874 -0.4064)
			(end 0.7874 -0.4064)
			(stroke
				(width 0.1524)
				(type default)
			)
			(layer "F.SilkS")
		)
		(fp_line
			(start 0.7874 0.4064)
			(end -0.7874 0.4064)
			(stroke
				(width 0.1524)
				(type default)
			)
			(layer "F.SilkS")
		)
		(fp_line
			(start -0.7874 0.4064)
			(end -0.7874 -0.4064)
			(stroke
				(width 0.1524)
				(type default)
			)
			(layer "F.SilkS")
		)
		(fp_line
			(start -0.12065 -0.305054)
			(end -0.12065 -0.2794)
			(stroke
				(width 0.1)
				(type default)
			)
			(layer "F.Fab")
		)
		(fp_line
			(start -0.67945 -0.305054)
			(end -0.12065 -0.305054)
			(stroke
				(width 0.1)
				(type default)
			)
			(layer "F.Fab")
		)
		(fp_line
			(start 0.67945 -0.3048)
			(end 0.67945 0.3048)
			(stroke
				(width 0.1)
				(type default)
			)
			(layer "F.Fab")
		)
		(fp_line
			(start 0.12065 -0.3048)
			(end 0.67945 -0.3048)
			(stroke
				(width 0.1)
				(type default)
			)
			(layer "F.Fab")
		)
		(fp_line
			(start 0.12065 -0.2794)
			(end 0.12065 -0.3048)
			(stroke
				(width 0.1)
				(type default)
			)
			(layer "F.Fab")
		)
		(fp_line
			(start -0.12065 -0.2794)
			(end 0.12065 -0.2794)
			(stroke
				(width 0.1)
				(type default)
			)
			(layer "F.Fab")
		)
		(fp_line
			(start 0.120396 0.2794)
			(end -0.12065 0.2794)
			(stroke
				(width 0.1)
				(type default)
			)
			(layer "F.Fab")
		)
		(fp_line
			(start -0.12065 0.2794)
			(end -0.12065 0.3048)
			(stroke
				(width 0.1)
				(type default)
			)
			(layer "F.Fab")
		)
		(fp_line
			(start 0.67945 0.3048)
			(end 0.120396 0.3048)
			(stroke
				(width 0.1)
				(type default)
			)
			(layer "F.Fab")
		)
		(fp_line
			(start 0.120396 0.3048)
			(end 0.120396 0.2794)
			(stroke
				(width 0.1)
				(type default)
			)
			(layer "F.Fab")
		)
		(fp_line
			(start -0.12065 0.3048)
			(end -0.67945 0.3048)
			(stroke
				(width 0.1)
				(type default)
			)
			(layer "F.Fab")
		)
		(fp_line
			(start -0.67945 0.3048)
			(end -0.67945 -0.305054)
			(stroke
				(width 0.1)
				(type default)
			)
			(layer "F.Fab")
		)
		(pad "1" smd circle
			(at -0.40005 0 90)
			(size 0 0)
			(layers "F.Cu" "F.Mask" "F.Paste")
			(net "RST_SSD0_PERST_N")
		)
		(pad "2" smd circle
			(at 0.40005 0 90)
			(size 0 0)
			(layers "F.Cu" "F.Mask" "F.Paste")
			(net "RST_SSD0_PERST_R_N")
		)
	)
	(footprint ""
		(layer "F.Cu")
		(at 242.205256 -228.57206)
		(property "Reference" "R6760"
			(at 0 0 0)
			(layer "F.SilkS")
			(hide yes)
			(effects
				(font
					(size 1.27 1.27)
				)
			)
		)
		(property "Value" ""
			(at 0 0 0)
			(layer "F.Fab")
			(effects
				(font
					(size 1.27 1.27)
				)
			)
		)
		(duplicate_pad_numbers_are_jumpers no)
		(fp_line
			(start 0.7874 -0.4064)
			(end 0.7874 0.4064)
			(stroke
				(width 0.1524)
				(type default)
			)
			(layer "F.SilkS")
		)
		(fp_line
			(start -0.67945 -0.305054)
			(end -0.12065 -0.305054)
			(stroke
				(width 0.1)
				(type default)
			)
			(layer "F.Fab")
		)
		(fp_line
			(start -0.67945 0.3048)
			(end -0.67945 -0.305054)
			(stroke
				(width 0.1)
				(type default)
			)
			(layer "F.Fab")
		)
		(fp_line
			(start -0.12065 -0.305054)
			(end -0.12065 -0.2794)
			(stroke
				(width 0.1)
				(type default)
			)
			(layer "F.Fab")
		)
		(fp_line
			(start -0.12065 -0.2794)
			(end 0.12065 -0.2794)
			(stroke
				(width 0.1)
				(type default)
			)
			(layer "F.Fab")
		)
		(fp_line
			(start -0.12065 0.2794)
			(end -0.12065 0.3048)
			(stroke
				(width 0.1)
				(type default)
			)
			(layer "F.Fab")
		)
		(fp_line
			(start -0.12065 0.3048)
			(end -0.67945 0.3048)
			(stroke
				(width 0.1)
				(type default)
			)
			(layer "F.Fab")
		)
		(fp_line
			(start 0.120396 0.2794)
			(end -0.12065 0.2794)
			(stroke
				(width 0.1)
				(type default)
			)
			(layer "F.Fab")
		)
		(fp_line
			(start 0.120396 0.3048)
			(end 0.120396 0.2794)
			(stroke
				(width 0.1)
				(type default)
			)
			(layer "F.Fab")
		)
		(fp_line
			(start 0.12065 -0.3048)
			(end 0.67945 -0.3048)
			(stroke
				(width 0.1)
				(type default)
			)
			(layer "F.Fab")
		)
		(fp_line
			(start 0.12065 -0.2794)
			(end 0.12065 -0.3048)
			(stroke
				(width 0.1)
				(type default)
			)
			(layer "F.Fab")
		)
		(fp_line
			(start 0.67945 -0.3048)
			(end 0.67945 0.3048)
			(stroke
				(width 0.1)
				(type default)
			)
			(layer "F.Fab")
		)
		(fp_line
			(start 0.67945 0.3048)
			(end 0.120396 0.3048)
			(stroke
				(width 0.1)
				(type default)
			)
			(layer "F.Fab")
		)
		(pad "1" smd circle
			(at -0.40005 0)
			(size 0 0)
			(layers "F.Cu" "F.Mask" "F.Paste")
			(net "USB2_BIC_DP")
		)
		(pad "2" smd circle
			(at 0.40005 0)
			(size 0 0)
			(layers "F.Cu" "F.Mask" "F.Paste")
			(net "GND")
		)
	)
)
